(kicad_pcb
	(version 20260206)
	(generator "pcbnew")
	(generator_version "10.0")
	(general
		(thickness 1.6)
		(legacy_teardrops no)
	)
	(paper "A4")
	(title_block
		(title "ptb — Lightning_PTB_BRD.brd")
		(comment 1 "Lightning (Wiwynn / Facebook NVMe JBOF) / footprints 1-7 of 61")
	)
	(layers
		(0 "F.Cu" signal "TOP")
		(4 "In1.Cu" signal "L2GND")
		(6 "In2.Cu" signal "L3VCC")
		(2 "B.Cu" signal "BOTTOM")
		(9 "F.Adhes" user "F.Adhesive")
		(11 "B.Adhes" user "B.Adhesive")
		(13 "F.Paste" user "Package Geometry/Pastemask Top")
		(15 "B.Paste" user "Package Geometry/Pastemask Bottom")
		(5 "F.SilkS" user "Ref Des/Silkscreen Top")
		(7 "B.SilkS" user "Ref Des/Silkscreen Bottom")
		(1 "F.Mask" user "Board Geometry/Soldermask Top")
		(3 "B.Mask" user "Board Geometry/Soldermask Bottom")
		(17 "Dwgs.User" user "User.Drawings")
		(19 "Cmts.User" user "User.Comments")
		(21 "Eco1.User" user "User.Eco1")
		(23 "Eco2.User" user "User.Eco2")
		(25 "Edge.Cuts" user "Board Geometry/Outline")
		(27 "Margin" user)
		(31 "F.CrtYd" user "Package Geometry/Place Bound Top")
		(29 "B.CrtYd" user "Package Geometry/Place Bound Bottom")
		(35 "F.Fab" user "Ref Des/Assembly Top")
		(33 "B.Fab" user "Ref Des/Assembly Bottom")
	)
	(footprint ""
		(layer "F.Cu")
		(at 123.85675 -47.164244 180)
		(property "Reference" "TC3"
			(at 0 0 180)
			(layer "F.SilkS")
			(hide yes)
			(effects
				(font
					(size 1.27 1.27)
				)
			)
		)
		(property "Value" "ST68U16VDM-1-GP"
			(at 0 -9.6012 180)
			(unlocked yes)
			(layer "F.Fab")
			(hide yes)
			(effects
				(font
					(size 1.016 1.016)
					(thickness 0.1524)
				)
			)
		)
		(property "Device Type" "CT7343H79"
			(at 0 -11.1252 180)
			(unlocked yes)
			(layer "F.Fab")
			(hide yes)
			(effects
				(font
					(size 1.016 1.016)
					(thickness 0.1524)
				)
			)
		)
		(duplicate_pad_numbers_are_jumpers no)
		(fp_line
			(start 2.286 4.8768)
			(end -2.286 4.8768)
			(stroke
				(width 0.1524)
				(type default)
			)
			(layer "F.SilkS")
		)
		(fp_line
			(start 2.286 2.032)
			(end 2.286 4.8768)
			(stroke
				(width 0.1524)
				(type default)
			)
			(layer "F.SilkS")
		)
		(fp_line
			(start 2.286 -2.032)
			(end 2.286 -4.8768)
			(stroke
				(width 0.1524)
				(type default)
			)
			(layer "F.SilkS")
		)
		(fp_line
			(start 2.286 -4.8768)
			(end -2.286 -4.8768)
			(stroke
				(width 0.1524)
				(type default)
			)
			(layer "F.SilkS")
		)
		(fp_line
			(start 2.1082 -4.699)
			(end -2.1082 -4.699)
			(stroke
				(width 0.508)
				(type default)
			)
			(layer "F.SilkS")
		)
		(fp_line
			(start -2.286 4.8768)
			(end -2.286 2.032)
			(stroke
				(width 0.1524)
				(type default)
			)
			(layer "F.SilkS")
		)
		(fp_line
			(start -2.286 -4.8768)
			(end -2.286 -2.032)
			(stroke
				(width 0.1524)
				(type default)
			)
			(layer "F.SilkS")
		)
		(fp_rect
			(start -2.1463 3.6449)
			(end 2.1463 -3.6449)
			(stroke
				(width 0)
				(type default)
			)
			(fill no)
			(layer "F.CrtYd")
		)
		(fp_poly
			(pts
				(xy -2.54 4.953) (xy -2.54 4.2926) (xy -3.81 4.2926) (xy -3.81 -4.2926) (xy -2.54 -4.2926) (xy -2.54 -4.953)
				(xy 2.54 -4.953) (xy 2.54 -4.2926) (xy 3.81 -4.2926) (xy 3.81 -1.6256) (xy 2.1463 -1.6256) (xy 2.1463 -3.6449)
				(xy -2.1463 -3.6449) (xy -2.1463 3.6449) (xy 2.1463 3.6449) (xy 2.1463 -1.6129) (xy 3.81 -1.6129)
				(xy 3.81 4.2926) (xy 2.54 4.2926) (xy 2.54 4.953)
			)
			(stroke
				(width 0)
				(type default)
			)
			(fill no)
			(layer "F.CrtYd")
		)
		(fp_rect
			(start 2.54 4.2926)
			(end 3.81 -4.2926)
			(stroke
				(width 0)
				(type default)
			)
			(fill no)
			(layer "F.Fab")
		)
		(fp_rect
			(start -2.54 4.953)
			(end 2.54 -4.953)
			(stroke
				(width 0)
				(type default)
			)
			(fill no)
			(layer "F.Fab")
		)
		(fp_rect
			(start -3.81 4.2926)
			(end -2.54 -4.2926)
			(stroke
				(width 0)
				(type default)
			)
			(fill no)
			(layer "F.Fab")
		)
		(pad "1" smd rect
			(at 0 -3.1496 180)
			(size 2.413 2.286)
			(layers "F.Cu" "F.Mask" "F.Paste")
			(net "P12V")
		)
		(pad "2" smd rect
			(at 0 3.1496 180)
			(size 2.413 2.286)
			(layers "F.Cu" "F.Mask" "F.Paste")
			(net "GND")
		)
		(zone
			(layer "F.Cu")
			(hatch none 0.5)
			(connect_pads
				(clearance 0)
			)
			(min_thickness 0.25)
			(keepout
				(tracks allowed)
				(vias not_allowed)
				(pads allowed)
				(copperpour not_allowed)
				(footprints allowed)
			)
			(placement
				(enabled no)
				(sheetname "")
			)
			(fill
				(thermal_gap 0.5)
				(thermal_bridge_width 0.5)
				(island_removal_mode 0)
			)
			(polygon
				(pts
					(xy 122.34545 -45.475144) (xy 122.34545 -42.566844) (xy 125.36805 -42.566844) (xy 125.36805 -45.462444)
					(xy 125.36805 -45.792644) (xy 122.34545 -45.792644)
				)
			)
		)
		(zone
			(layer "F.Cu")
			(hatch none 0.5)
			(connect_pads
				(clearance 0)
			)
			(min_thickness 0.25)
			(keepout
				(tracks allowed)
				(vias not_allowed)
				(pads allowed)
				(copperpour not_allowed)
				(footprints allowed)
			)
			(placement
				(enabled no)
				(sheetname "")
			)
			(fill
				(thermal_gap 0.5)
				(thermal_bridge_width 0.5)
				(island_removal_mode 0)
			)
			(polygon
				(pts
					(xy 125.36805 -51.761644) (xy 122.34545 -51.761644) (xy 122.34545 -48.866044) (xy 122.34545 -48.535844)
					(xy 125.36805 -48.535844) (xy 125.36805 -48.866044)
				)
			)
		)
	)
	(footprint ""
		(layer "F.Cu")
		(at 136.152382 -67.048634 90)
		(property "Reference" "R387"
			(at 0 0 90)
			(layer "F.SilkS")
			(hide yes)
			(effects
				(font
					(size 1.27 1.27)
				)
			)
		)
		(property "Value" "0R2J-2-GP"
			(at 0.064008 -3.993896 90)
			(unlocked yes)
			(layer "F.Fab")
			(hide yes)
			(effects
				(font
					(size 1.016 1.016)
					(thickness 0.1524)
				)
			)
		)
		(property "Device Type" "R402H16"
			(at 0.064008 -5.517896 90)
			(unlocked yes)
			(layer "F.Fab")
			(hide yes)
			(effects
				(font
					(size 1.016 1.016)
					(thickness 0.1524)
				)
			)
		)
		(duplicate_pad_numbers_are_jumpers no)
		(fp_line
			(start 0.508 -0.9398)
			(end -0.508 -0.9398)
			(stroke
				(width 0.1524)
				(type default)
			)
			(layer "F.SilkS")
		)
		(fp_line
			(start -0.508 -0.9398)
			(end -0.508 0.9398)
			(stroke
				(width 0.1524)
				(type default)
			)
			(layer "F.SilkS")
		)
		(fp_rect
			(start -0.508 0.9398)
			(end 0.508 -0.9398)
			(stroke
				(width 0)
				(type default)
			)
			(fill no)
			(layer "F.CrtYd")
		)
		(fp_rect
			(start -0.508 0.9398)
			(end 0.508 -0.9398)
			(stroke
				(width 0)
				(type default)
			)
			(fill no)
			(layer "F.Fab")
		)
		(pad "1" smd custom
			(at 0 -0.4445 90)
			(size 0.1397 0.1397)
			(layers "F.Cu" "F.Mask" "F.Paste")
			(net "I2C_C_BUF_SCL")
			(options
				(clearance outline)
				(anchor circle)
			)
			(primitives
				(gr_poly
					(pts
						(arc
							(start -0.1778 -0.2794)
							(mid -0.249642 -0.249642)
							(end -0.2794 -0.1778)
						)
						(arc
							(start -0.2794 0.1778)
							(mid -0.249642 0.249642)
							(end -0.1778 0.2794)
						)
						(arc
							(start 0.1778 0.2794)
							(mid 0.249642 0.249642)
							(end 0.2794 0.1778)
						)
						(arc
							(start 0.2794 -0.1778)
							(mid 0.249642 -0.249642)
							(end 0.1778 -0.2794)
						)
					)
					(width 0)
					(fill yes)
				)
			)
		)
		(pad "2" smd custom
			(at 0 0.4445 90)
			(size 0.1397 0.1397)
			(layers "F.Cu" "F.Mask" "F.Paste")
			(net "I2C_C_BUF_SCL_CONN")
			(options
				(clearance outline)
				(anchor circle)
			)
			(primitives
				(gr_poly
					(pts
						(arc
							(start -0.1778 -0.2794)
							(mid -0.249642 -0.249642)
							(end -0.2794 -0.1778)
						)
						(arc
							(start -0.2794 0.1778)
							(mid -0.249642 0.249642)
							(end -0.1778 0.2794)
						)
						(arc
							(start 0.1778 0.2794)
							(mid 0.249642 0.249642)
							(end 0.2794 0.1778)
						)
						(arc
							(start 0.2794 -0.1778)
							(mid 0.249642 -0.249642)
							(end 0.1778 -0.2794)
						)
					)
					(width 0)
					(fill yes)
				)
			)
		)
	)
	(footprint ""
		(layer "F.Cu")
		(at 9.679686 -92.946982)
		(property "Reference" "C358"
			(at 0 0 0)
			(layer "F.SilkS")
			(hide yes)
			(effects
				(font
					(size 1.27 1.27)
				)
			)
		)
		(property "Value" "SC220P50V3JN-GP"
			(at 0 -2.8194 0)
			(unlocked yes)
			(layer "F.Fab")
			(hide yes)
			(effects
				(font
					(size 1.016 1.016)
					(thickness 0.1524)
				)
			)
		)
		(property "Device Type" "C603H36"
			(at 0 -4.3434 0)
			(unlocked yes)
			(layer "F.Fab")
			(hide yes)
			(effects
				(font
					(size 1.016 1.016)
					(thickness 0.1524)
				)
			)
		)
		(duplicate_pad_numbers_are_jumpers no)
		(fp_line
			(start 0.508 0)
			(end -0.508 0)
			(stroke
				(width 0.2032)
				(type default)
			)
			(layer "F.SilkS")
		)
		(fp_rect
			(start -0.5842 1.3335)
			(end 0.5842 -1.3335)
			(stroke
				(width 0)
				(type default)
			)
			(fill no)
			(layer "F.CrtYd")
		)
		(fp_rect
			(start -0.5842 1.3335)
			(end 0.5842 -1.3335)
			(stroke
				(width 0)
				(type default)
			)
			(fill no)
			(layer "F.Fab")
		)
		(pad "1" smd custom
			(at 0 -0.762)
			(size 0.2159 0.2159)
			(layers "F.Cu" "F.Mask" "F.Paste")
			(net "I2C_C_SCL")
			(options
				(clearance outline)
				(anchor circle)
			)
			(primitives
				(gr_poly
					(pts
						(arc
							(start -0.3302 -0.4318)
							(mid -0.402042 -0.402042)
							(end -0.4318 -0.3302)
						)
						(arc
							(start -0.4318 0.3302)
							(mid -0.402042 0.402042)
							(end -0.3302 0.4318)
						)
						(arc
							(start 0.3302 0.4318)
							(mid 0.402042 0.402042)
							(end 0.4318 0.3302)
						)
						(arc
							(start 0.4318 -0.3302)
							(mid 0.402042 -0.402042)
							(end 0.3302 -0.4318)
						)
					)
					(width 0)
					(fill yes)
				)
			)
		)
		(pad "2" smd custom
			(at 0 0.762)
			(size 0.2159 0.2159)
			(layers "F.Cu" "F.Mask" "F.Paste")
			(net "GND")
			(options
				(clearance outline)
				(anchor circle)
			)
			(primitives
				(gr_poly
					(pts
						(arc
							(start -0.3302 -0.4318)
							(mid -0.402042 -0.402042)
							(end -0.4318 -0.3302)
						)
						(arc
							(start -0.4318 0.3302)
							(mid -0.402042 0.402042)
							(end -0.3302 0.4318)
						)
						(arc
							(start 0.3302 0.4318)
							(mid 0.402042 0.402042)
							(end 0.4318 0.3302)
						)
						(arc
							(start 0.4318 -0.3302)
							(mid 0.402042 -0.402042)
							(end 0.3302 -0.4318)
						)
					)
					(width 0)
					(fill yes)
				)
			)
		)
	)
	(footprint ""
		(layer "F.Cu")
		(at 155.66009 -98.799904 90)
		(property "Reference" "Q31"
			(at 0 0 90)
			(layer "F.SilkS")
			(hide yes)
			(effects
				(font
					(size 1.27 1.27)
				)
			)
		)
		(property "Value" "SENSOR-2P-GP-U"
			(at -3.4036 1.3462 90)
			(unlocked yes)
			(layer "F.Fab")
			(hide yes)
			(effects
				(font
					(size 1.016 1.016)
					(thickness 0.1524)
				)
			)
		)
		(property "Device Type" "SNR2N4036-UH166"
			(at -3.4036 -0.1778 90)
			(unlocked yes)
			(layer "F.Fab")
			(hide yes)
			(effects
				(font
					(size 1.016 1.016)
					(thickness 0.1524)
				)
			)
		)
		(duplicate_pad_numbers_are_jumpers no)
		(fp_line
			(start 2.0574 -2.6543)
			(end -2.1844 -2.6543)
			(stroke
				(width 0.1524)
				(type default)
			)
			(layer "F.SilkS")
		)
		(fp_line
			(start -2.1844 -2.6543)
			(end -2.1844 2.6543)
			(stroke
				(width 0.1524)
				(type default)
			)
			(layer "F.SilkS")
		)
		(fp_line
			(start 2.0574 2.6543)
			(end 2.0574 -2.6543)
			(stroke
				(width 0.1524)
				(type default)
			)
			(layer "F.SilkS")
		)
		(fp_line
			(start -2.1844 2.6543)
			(end 2.0574 2.6543)
			(stroke
				(width 0.1524)
				(type default)
			)
			(layer "F.SilkS")
		)
		(fp_poly
			(pts
				(xy -2.2098 2.0066) (xy -2.2098 1.3208) (xy -2.8702 1.3208) (xy -2.8702 2.0066)
			)
			(stroke
				(width 0)
				(type default)
			)
			(fill yes)
			(layer "F.SilkS")
		)
		(fp_rect
			(start -1.8034 1.9939)
			(end 1.8034 -1.9939)
			(stroke
				(width 0)
				(type default)
			)
			(fill no)
			(layer "F.CrtYd")
		)
		(fp_poly
			(pts
				(xy -2.4384 2.7305) (xy -2.4384 -2.7305) (xy 2.3114 -2.7305) (xy 2.3114 1.98882) (xy 1.8034 1.98882)
				(xy 1.8034 -1.9939) (xy -1.8034 -1.9939) (xy -1.8034 1.9939) (xy 2.3114 1.9939) (xy 2.3114 2.7305)
			)
			(stroke
				(width 0)
				(type default)
			)
			(fill no)
			(layer "F.CrtYd")
		)
		(fp_rect
			(start -2.4384 2.7305)
			(end 2.3114 -2.7305)
			(stroke
				(width 0)
				(type default)
			)
			(fill no)
			(layer "F.Fab")
		)
		(fp_text user "E"
			(at 2.038096 -3.71729 90)
			(unlocked yes)
			(layer "F.SilkS")
			(effects
				(font
					(size 1.016 1.016)
					(thickness 0.1524)
				)
			)
		)
		(fp_text user "C"
			(at 2.038096 3.64871 90)
			(unlocked yes)
			(layer "F.SilkS")
			(effects
				(font
					(size 1.016 1.016)
					(thickness 0.1524)
				)
			)
		)
		(pad "C" smd rect
			(at -0.374904 1.455674 90)
			(size 3.0988 1.8796)
			(layers "F.Cu" "F.Mask" "F.Paste")
			(net "DETECTOR_C")
		)
		(pad "E" smd rect
			(at -0.374904 -1.455674 90)
			(size 3.0988 1.8796)
			(layers "F.Cu" "F.Mask" "F.Paste")
			(net "IR_SWITCH_E")
		)
	)
	(footprint ""
		(layer "F.Cu")
		(at 138.684 -106.426 -90)
		(property "Reference" "R390"
			(at 0 0 270)
			(layer "F.SilkS")
			(hide yes)
			(effects
				(font
					(size 1.27 1.27)
				)
			)
		)
		(property "Value" "0R2J-2-GP"
			(at 0.064008 -3.993896 270)
			(unlocked yes)
			(layer "F.Fab")
			(hide yes)
			(effects
				(font
					(size 1.016 1.016)
					(thickness 0.1524)
				)
			)
		)
		(property "Device Type" "R402H16"
			(at 0.064008 -5.517896 270)
			(unlocked yes)
			(layer "F.Fab")
			(hide yes)
			(effects
				(font
					(size 1.016 1.016)
					(thickness 0.1524)
				)
			)
		)
		(duplicate_pad_numbers_are_jumpers no)
		(fp_line
			(start -0.508 -0.9398)
			(end -0.508 0.9398)
			(stroke
				(width 0.1524)
				(type default)
			)
			(layer "F.SilkS")
		)
		(fp_line
			(start 0.508 -0.9398)
			(end -0.508 -0.9398)
			(stroke
				(width 0.1524)
				(type default)
			)
			(layer "F.SilkS")
		)
		(fp_rect
			(start -0.508 0.9398)
			(end 0.508 -0.9398)
			(stroke
				(width 0)
				(type default)
			)
			(fill no)
			(layer "F.CrtYd")
		)
		(fp_rect
			(start -0.508 0.9398)
			(end 0.508 -0.9398)
			(stroke
				(width 0)
				(type default)
			)
			(fill no)
			(layer "F.Fab")
		)
		(pad "1" smd custom
			(at 0 -0.4445 270)
			(size 0.1397 0.1397)
			(layers "F.Cu" "F.Mask" "F.Paste")
			(net "TPS2490_DISABLE")
			(options
				(clearance outline)
				(anchor circle)
			)
			(primitives
				(gr_poly
					(pts
						(arc
							(start -0.1778 -0.2794)
							(mid -0.249642 -0.249642)
							(end -0.2794 -0.1778)
						)
						(arc
							(start -0.2794 0.1778)
							(mid -0.249642 0.249642)
							(end -0.1778 0.2794)
						)
						(arc
							(start 0.1778 0.2794)
							(mid 0.249642 0.249642)
							(end 0.2794 0.1778)
						)
						(arc
							(start 0.2794 -0.1778)
							(mid 0.249642 -0.249642)
							(end 0.1778 -0.2794)
						)
					)
					(width 0)
					(fill yes)
				)
			)
		)
		(pad "2" smd custom
			(at 0 0.4445 270)
			(size 0.1397 0.1397)
			(layers "F.Cu" "F.Mask" "F.Paste")
			(net "GND")
			(options
				(clearance outline)
				(anchor circle)
			)
			(primitives
				(gr_poly
					(pts
						(arc
							(start -0.1778 -0.2794)
							(mid -0.249642 -0.249642)
							(end -0.2794 -0.1778)
						)
						(arc
							(start -0.2794 0.1778)
							(mid -0.249642 0.249642)
							(end -0.1778 0.2794)
						)
						(arc
							(start 0.1778 0.2794)
							(mid 0.249642 0.249642)
							(end 0.2794 0.1778)
						)
						(arc
							(start 0.2794 -0.1778)
							(mid 0.249642 -0.249642)
							(end 0.1778 -0.2794)
						)
					)
					(width 0)
					(fill yes)
				)
			)
		)
	)
	(footprint ""
		(layer "F.Cu")
		(at 10.492486 -98.872802 180)
		(property "Reference" "C345"
			(at 0 0 180)
			(layer "F.SilkS")
			(hide yes)
			(effects
				(font
					(size 1.27 1.27)
				)
			)
		)
		(property "Value" "SCD01U50V2KX-1GP"
			(at 1.1811 -2.7051 180)
			(unlocked yes)
			(layer "F.Fab")
			(hide yes)
			(effects
				(font
					(size 1.016 1.016)
					(thickness 0.1524)
				)
			)
		)
		(property "Device Type" "C402H22"
			(at 1.1811 -4.2291 180)
			(unlocked yes)
			(layer "F.Fab")
			(hide yes)
			(effects
				(font
					(size 1.016 1.016)
					(thickness 0.1524)
				)
			)
		)
		(duplicate_pad_numbers_are_jumpers no)
		(fp_rect
			(start -0.4318 0.9525)
			(end 0.4318 -0.9525)
			(stroke
				(width 0)
				(type default)
			)
			(fill no)
			(layer "F.CrtYd")
		)
		(fp_rect
			(start -0.4318 0.9525)
			(end 0.4318 -0.9525)
			(stroke
				(width 0)
				(type default)
			)
			(fill no)
			(layer "F.Fab")
		)
		(pad "1" smd custom
			(at 0 -0.4445 180)
			(size 0.1524 0.1524)
			(layers "F.Cu" "F.Mask" "F.Paste")
			(net "P3V3")
			(options
				(clearance outline)
				(anchor circle)
			)
			(primitives
				(gr_poly
					(pts
						(arc
							(start 0.3048 -0.2032)
							(mid 0.275042 -0.275042)
							(end 0.2032 -0.3048)
						)
						(arc
							(start -0.2032 -0.3048)
							(mid -0.275042 -0.275042)
							(end -0.3048 -0.2032)
						)
						(arc
							(start -0.3048 0.2032)
							(mid -0.275042 0.275042)
							(end -0.2032 0.3048)
						)
						(arc
							(start 0.2032 0.3048)
							(mid 0.275042 0.275042)
							(end 0.3048 0.2032)
						)
					)
					(width 0)
					(fill yes)
				)
			)
		)
		(pad "2" smd custom
			(at 0 0.4445 180)
			(size 0.1524 0.1524)
			(layers "F.Cu" "F.Mask" "F.Paste")
			(net "GND")
			(options
				(clearance outline)
				(anchor circle)
			)
			(primitives
				(gr_poly
					(pts
						(arc
							(start 0.3048 -0.2032)
							(mid 0.275042 -0.275042)
							(end 0.2032 -0.3048)
						)
						(arc
							(start -0.2032 -0.3048)
							(mid -0.275042 -0.275042)
							(end -0.3048 -0.2032)
						)
						(arc
							(start -0.3048 0.2032)
							(mid -0.275042 0.275042)
							(end -0.2032 0.3048)
						)
						(arc
							(start 0.2032 0.3048)
							(mid 0.275042 0.275042)
							(end 0.3048 0.2032)
						)
					)
					(width 0)
					(fill yes)
				)
			)
		)
	)
	(footprint ""
		(layer "F.Cu")
		(at 139.826492 -82.838544)
		(property "Reference" "R378"
			(at 0 0 0)
			(layer "F.SilkS")
			(hide yes)
			(effects
				(font
					(size 1.27 1.27)
				)
			)
		)
		(property "Value" "68R5J-GP"
			(at 0 -8.9535 0)
			(unlocked yes)
			(layer "F.Fab")
			(hide yes)
			(effects
				(font
					(size 1.27 1.016)
					(thickness 0.1524)
				)
			)
		)
		(property "Device Type" "R805H24"
			(at 0 -10.6299 0)
			(unlocked yes)
			(layer "F.Fab")
			(hide yes)
			(effects
				(font
					(size 1.27 1.016)
					(thickness 0.1524)
				)
			)
		)
		(duplicate_pad_numbers_are_jumpers no)
		(fp_line
			(start -0.889 -1.7018)
			(end -0.889 0.2794)
			(stroke
				(width 0.1524)
				(type default)
			)
			(layer "F.SilkS")
		)
		(fp_line
			(start -0.889 0.0762)
			(end -0.889 1.7018)
			(stroke
				(width 0.1524)
				(type default)
			)
			(layer "F.SilkS")
		)
		(fp_line
			(start -0.889 1.7018)
			(end 0.889 1.7018)
			(stroke
				(width 0.1524)
				(type default)
			)
			(layer "F.SilkS")
		)
		(fp_line
			(start 0.889 -1.7018)
			(end -0.889 -1.7018)
			(stroke
				(width 0.1524)
				(type default)
			)
			(layer "F.SilkS")
		)
		(fp_line
			(start 0.889 -1.7018)
			(end 0.889 -0.381)
			(stroke
				(width 0.1524)
				(type default)
			)
			(layer "F.SilkS")
		)
		(fp_line
			(start 0.889 1.7018)
			(end 0.889 -0.508)
			(stroke
				(width 0.1524)
				(type default)
			)
			(layer "F.SilkS")
		)
		(fp_poly
			(pts
				(xy 0.9652 -1.778) (xy 0.9652 1.778) (xy -0.9652 1.778) (xy -0.9652 -1.778)
			)
			(stroke
				(width 0)
				(type default)
			)
			(fill no)
			(layer "F.CrtYd")
		)
		(fp_rect
			(start -0.9652 1.778)
			(end 0.9652 -1.778)
			(stroke
				(width 0)
				(type default)
			)
			(fill no)
			(layer "F.Fab")
		)
		(pad "1" smd rect
			(at 0 -0.9652)
			(size 1.397 1.143)
			(layers "F.Cu" "F.Mask" "F.Paste")
			(net "EMITTER_K")
		)
		(pad "2" smd rect
			(at 0 0.9652)
			(size 1.397 1.143)
			(layers "F.Cu" "F.Mask" "F.Paste")
			(net "GND")
		)
	)
)
